#ISCELL
  mstr_misc dns *
  *
#ISCELL
  pure_quanta quanta_title_block_c *
  *
#ISCELL
  pure_quanta_power universal_gnd *
  page477_i1
#CELL
  pure_quanta q_res *
  page477_i10
#CELL
  pure_quanta q_res *
  page477_i11
#ISCELL
  pure_quanta_power universal_gnd *
  page477_i12
#CELL
  pure_quanta q_res *
  page477_i13
#CELL
  pure_quanta q_res *
  page477_i14
#CELL
  pure_quanta q_res *
  page477_i15
#ISCELL
  pure_quanta_power universal_gnd *
  page477_i16
#ISCELL
  pure_quanta_power vcc15 *
  page477_i17
#CELL
  pure_quanta q_res *
  page477_i2
#ISCELL
  standard offpage *
  page477_i20
#ISCELL
  standard offpage *
  page477_i21
#CELL
  pure_quanta q_res *
  page477_i22
#CELL
  pure_quanta q_res *
  page477_i23
#ISCELL
  pure_quanta_power universal_gnd *
  page477_i24
#ISCELL
  pure_quanta_power vcc15 *
  page477_i25
#ISCELL
  pure_quanta_power vcc15 *
  page477_i26
#CELL
  pure_quanta q_res *
  page477_i27
#CELL
  pure_quanta q_cap *
  page477_i28
#ISCELL
  standard offpage *
  page477_i29
#CELL
  pure_quanta q_res *
  page477_i3
#ISCELL
  standard offpage *
  page477_i30
#CELL
  pure_quanta q_res *
  page477_i31
#CELL
  pure_quanta q_res *
  page477_i32
#CELL
  pure_quanta q_res *
  page477_i33
#ISCELL
  pure_quanta_power vcc15 *
  page477_i34
#ISCELL
  pure_quanta_power vcc15 *
  page477_i35
#CELL
  pure_quanta q_res *
  page477_i36
#CELL
  pure_quanta q_res *
  page477_i37
#CELL
  pure_quanta q_res *
  page477_i38
#CELL
  pure_quanta q_res *
  page477_i39
#ISCELL
  pure_quanta_power universal_gnd *
  page477_i4
#ISCELL
  pure_quanta_power universal_gnd *
  page477_i41
#CELL
  pure_quanta q_res *
  page477_i42
#CELL
  pure_quanta q_res *
  page477_i43
#CELL
  pure_quanta q_res *
  page477_i44
#CELL
  pure_quanta q_cap *
  page477_i45
#CELL
  pure_quanta q_res *
  page477_i46
#ISCELL
  pure_quanta_power universal_gnd *
  page477_i47
#CELL
  pure_quanta q_cap *
  page477_i48
#ISCELL
  pure_quanta_power universal_gnd *
  page477_i49
#CELL
  pure_quanta q_cap *
  page477_i5
#ISCELL
  pure_quanta_power universal_gnd *
  page477_i50
#CELL
  pure_quanta q_cap *
  page477_i51
#CELL
  pure_quanta q_res *
  page477_i52
#ISCELL
  pure_quanta_power universal_gnd *
  page477_i53
#CELL
  pure_quanta q_res *
  page477_i54
#ISCELL
  pure_quanta_power universal_gnd *
  page477_i55
#CELL
  pure_quanta q_res *
  page477_i56
#CELL
  pure_quanta q_res *
  page477_i57
#CELL
  pure_quanta q_res *
  page477_i58
#ISCELL
  pure_quanta_power universal_gnd *
  page477_i59
#ISCELL
  pure_quanta_power vcc15 *
  page477_i6
#ISCELL
  pure_quanta_power universal_gnd *
  page477_i60
#ISCELL
  pure_quanta_power universal_gnd *
  page477_i61
#ISCELL
  pure_quanta_power universal_gnd *
  page477_i62
#ISCELL
  pure_quanta_power universal_gnd *
  page477_i63
#CELL
  pure_quanta q_res *
  page477_i64
#CELL
  pure_quanta q_res *
  page477_i65
#ISCELL
  pure_quanta_power universal_gnd *
  page477_i66
#ISCELL
  pure_quanta_power universal_gnd *
  page477_i67
#CELL
  pure_quanta q_res *
  page477_i68
#CELL
  pure_quanta q_res *
  page477_i69
#CELL
  pure_quanta q_res *
  page477_i7
#ISCELL
  pure_quanta_power universal_gnd *
  page477_i70
#ISCELL
  pure_quanta_power universal_gnd *
  page477_i71
#CELL
  pure_quanta q_cap *
  page477_i72
#CELL
  pure_quanta q_cap *
  page477_i73
#CELL
  pure_quanta q_cap *
  page477_i74
#CELL
  pure_quanta q_cap *
  page477_i75
#ISCELL
  standard offpage *
  page477_i76
#ISCELL
  standard offpage *
  page477_i77
#ISCELL
  standard offpage *
  page477_i78
#ISCELL
  standard offpage *
  page477_i79
#ISCELL
  pure_quanta_power vcc15 *
  page477_i8
#ISCELL
  pure_quanta_power universal_gnd *
  page477_i80
#ISCELL
  pure_quanta_power universal_gnd *
  page477_i81
#ISCELL
  standard offpage *
  page477_i82
#CELL
  pure_quanta q_res *
  page477_i83
#ISCELL
  pure_quanta_power vcc15 *
  page477_i84
#ISCELL
  standard offpage *
  page477_i85
#CELL
  pure_quanta q_res *
  page477_i86
#ISCELL
  pure_quanta_power vcc15 *
  page477_i87
#CELL
  pure_quanta isl69260irazt *
  page477_i88
#CELL
  pure_quanta q_res *
  page477_i89
#CELL
  pure_quanta q_res *
  page477_i90
#ISCELL
  pure_quanta_power universal_gnd *
  page477_i91
#CELL
  pure_quanta q_res *
  page477_i92
#CELL
  pure_quanta q_res *
  page477_i93
#ISCELL
  pure_quanta_power vcc15 *
  page477_i94
#CELL
  pure_quanta q_short *
  page477_i95
#CELL
  pure_quanta q_short *
  page477_i96
